# BASEBOARD_FAB2 (Tioga Pass) — schematic netlist excerpt (pin names and nets, part order shuffled) for the footprints in the layout excerpt that follows; sources: Cadence DE-HDL packaged netlist, KiCad conversion of Wiwynn_Tioga_Pass_MB.brd

J9L1  SCONN288_H44441003  SCONN  pkg PIP  page 88
  \12v\(1)  = P12V_NVDIMM_KLM
  VSS(93)  = GND
  DQ(4)  = M_M_DQ<4>
  VSS(92)  = GND
  DQ(0)  = M_M_DQ<0>
  VSS(91)  = GND
  DQS9P  = M_M_DQS_DP<9>
  DQS9N  = M_M_DQS_DN<9>
  VSS(90)  = GND
  DQ(6)  = M_M_DQ<6>
  VSS(89)  = GND
  DQ(2)  = M_M_DQ<2>
  VSS(88)  = GND
  DQ(12)  = M_M_DQ<12>
  VSS(87)  = GND
  DQ(8)  = M_M_DQ<8>
  VSS(86)  = GND
  DQS10P  = M_M_DQS_DP<10>
  DQS10N  = M_M_DQS_DN<10>
  VSS(85)  = GND
  DQ(14)  = M_M_DQ<14>
  VSS(84)  = GND
  DQ(10)  = M_M_DQ<10>
  VSS(83)  = GND
  DQ(20)  = M_M_DQ<20>
  VSS(82)  = GND
  DQ(16)  = M_M_DQ<16>
  VSS(81)  = GND
  DQS11P  = M_M_DQS_DP<11>
  DQS11N  = M_M_DQS_DN<11>
  VSS(80)  = GND
  DQ(22)  = M_M_DQ<22>
  VSS(79)  = GND
  DQ(18)  = M_M_DQ<18>
  VSS(78)  = GND
  DQ(28)  = M_M_DQ<28>
  VSS(77)  = GND
  DQ(24)  = M_M_DQ<24>
  VSS(76)  = GND
  DQS12P  = M_M_DQS_DP<12>
  DQS12N  = M_M_DQS_DN<12>
  VSS(75)  = GND
  DQ(30)  = M_M_DQ<30>
  VSS(74)  = GND
  DQ(26)  = M_M_DQ<26>
  VSS(73)  = GND
  CB(4)  = M_M_ECC<4>
  VSS(72)  = GND
  CB(0)  = M_M_ECC<0>
  VSS(71)  = GND
  DQS17P  = M_M_DQS_DP<17>
  DQS17N  = M_M_DQS_DN<17>
  VSS(70)  = GND
  CB(6)  = M_M_ECC<6>
  VSS(69)  = GND
  CB(2)  = M_M_ECC<2>
  VSS(68)  = GND
  RESET_N  = M_KLM_RST_N
  VDD(25)  = PVDDQ_KLM
  CKE(0)  = M_M_CKE<2>
  VDD(24)  = PVDDQ_KLM
  ACT_N  = M_M_ACT_N
  BG(0)  = M_M_BG<0>
  VDD(23)  = PVDDQ_KLM
  A12  = M_M_MA<12>
  A9  = M_M_MA<9>
  VDD(22)  = PVDDQ_KLM
  A8  = M_M_MA<8>
  A6  = M_M_MA<6>
  VDD(21)  = PVDDQ_KLM
  A3  = M_M_MA<3>
  A1  = M_M_MA<1>
  VDD(20)  = PVDDQ_KLM
  CK0P  = M_M_CLK_DP<2>
  CK0N  = M_M_CLK_DN<2>
  VDD(19)  = PVDDQ_KLM
  VTT(1)  = PVTT_KLM
  EVENT_N  = FM_DIMM_EVENT_COD_N
  A0  = M_M_MA<0>
  VDD(18)  = PVDDQ_KLM
  BA(0)  = M_M_BA<0>
  A16_RAS_N  = M_M_MA<16>
  VDD(17)  = PVDDQ_KLM
  S0_N  = M_M_CS_N<4>
  VDD(16)  = PVDDQ_KLM
  A15_CAS_N  = M_M_MA<15>
  ODT(0)  = M_M_ODT<2>
  VDD(15)  = PVDDQ_KLM
  S1_N  = M_M_CS_N<5>
  VDD(14)  = PVDDQ_KLM
  ODT(1)  = M_M_ODT<3>
  VDD(13)  = PVDDQ_KLM
  S2_N_C(0)  = M_M_CS_N<6>
  VSS(67)  = GND
  DQ(36)  = M_M_DQ<36>
  VSS(66)  = GND
  DQ(32)  = M_M_DQ<32>
  VSS(65)  = GND
  DQS13P  = M_M_DQS_DP<13>
  DQS13N  = M_M_DQS_DN<13>
  VSS(64)  = GND
  DQ(38)  = M_M_DQ<38>
  VSS(63)  = GND
  DQ(34)  = M_M_DQ<34>
  VSS(62)  = GND
  DQ(44)  = M_M_DQ<44>
  VSS(61)  = GND
  DQ(40)  = M_M_DQ<40>
  VSS(60)  = GND
  DQS14P  = M_M_DQS_DP<14>
  DQS14N  = M_M_DQS_DN<14>
  VSS(59)  = GND
  DQ(46)  = M_M_DQ<46>
  VSS(58)  = GND
  DQ(42)  = M_M_DQ<42>
  VSS(57)  = GND
  DQ(52)  = M_M_DQ<52>
  VSS(56)  = GND
  DQ(48)  = M_M_DQ<48>
  VSS(55)  = GND
  DQS15P  = M_M_DQS_DP<15>
  DQS15N  = M_M_DQS_DN<15>
  VSS(54)  = GND
  DQ(54)  = M_M_DQ<54>
  VSS(53)  = GND
  DQ(50)  = M_M_DQ<50>
  VSS(52)  = GND
  DQ(60)  = M_M_DQ<60>
  VSS(51)  = GND
  DQ(56)  = M_M_DQ<56>
  VSS(50)  = GND
  DQS16P  = M_M_DQS_DP<16>
  DQS16N  = M_M_DQS_DN<16>
  VSS(49)  = GND
  DQ(62)  = M_M_DQ<62>
  VSS(48)  = GND
  DQ(58)  = M_M_DQ<58>
  VSS(47)  = GND
  SA(0)  = PVPP_KLM
  SA(1)  = GND
  SCL  = SMB_DDR_KLM_VPP_SCL
  VPP(4)  = PVPP_KLM
  VPP(3)  = PVPP_KLM
  RFU(2)  = TP_CH_M_DIMM_M1_RFU_2
  \12v\(0)  = P12V_NVDIMM_KLM
  VREFCA  = M_M_VREF
  VSS(46)  = GND
  DQ(5)  = M_M_DQ<5>
  VSS(45)  = GND
  DQ(1)  = M_M_DQ<1>
  VSS(44)  = GND
  DQS0N  = M_M_DQS_DN<0>
  DQS0P  = M_M_DQS_DP<0>
  VSS(43)  = GND
  DQ(7)  = M_M_DQ<7>
  VSS(42)  = GND
  DQ(3)  = M_M_DQ<3>
  VSS(41)  = GND
  DQ(13)  = M_M_DQ<13>
  VSS(40)  = GND
  DQ(9)  = M_M_DQ<9>
  VSS(39)  = GND
  DQS1N  = M_M_DQS_DN<1>
  DQS1P  = M_M_DQS_DP<1>
  VSS(38)  = GND
  DQ(15)  = M_M_DQ<15>
  VSS(37)  = GND
  DQ(11)  = M_M_DQ<11>
  VSS(36)  = GND
  DQ(21)  = M_M_DQ<21>
  VSS(35)  = GND
  DQ(17)  = M_M_DQ<17>
  VSS(34)  = GND
  DQS2N  = M_M_DQS_DN<2>
  DQS2P  = M_M_DQS_DP<2>
  VSS(33)  = GND
  DQ(23)  = M_M_DQ<23>
  VSS(32)  = GND
  DQ(19)  = M_M_DQ<19>
  VSS(31)  = GND
  DQ(29)  = M_M_DQ<29>
  VSS(30)  = GND
  DQ(25)  = M_M_DQ<25>
  VSS(29)  = GND
  DQS3N  = M_M_DQS_DN<3>
  DQS3P  = M_M_DQS_DP<3>
  VSS(28)  = GND
  DQ(31)  = M_M_DQ<31>
  VSS(27)  = GND
  DQ(27)  = M_M_DQ<27>
  VSS(26)  = GND
  CB(5)  = M_M_ECC<5>
  VSS(25)  = GND
  CB(1)  = M_M_ECC<1>
  VSS(24)  = GND
  DQS8N  = M_M_DQS_DN<8>
  DQS8P  = M_M_DQS_DP<8>
  VSS(23)  = GND
  CB(7)  = M_M_ECC<7>
  VSS(22)  = GND
  CB(3)  = M_M_ECC<3>
  VSS(21)  = GND
  CKE(1)  = M_M_CKE<3>
  VDD(12)  = PVDDQ_KLM
  RFU(0)  = TP_CH_M_DIMM_M1_RFU_0
  VDD(11)  = PVDDQ_KLM
  BG(1)  = M_M_BG<1>
  ALERT_N  = M_M_ALERT_N
  VDD(10)  = PVDDQ_KLM
  A11  = M_M_MA<11>
  A7  = M_M_MA<7>
  VDD(9)  = PVDDQ_KLM
  A5  = M_M_MA<5>
  A4  = M_M_MA<4>
  VDD(8)  = PVDDQ_KLM
  A2  = M_M_MA<2>
  VDD(7)  = PVDDQ_KLM
  CK1P  = M_M_CLK_DP<3>
  CK1N  = M_M_CLK_DN<3>
  VDD(6)  = PVDDQ_KLM
  VTT(0)  = PVTT_KLM
  PAR  = M_M_PAR
  VDD(5)  = PVDDQ_KLM
  BA(1)  = M_M_BA<1>
  A10  = M_M_MA<10>
  VDD(4)  = PVDDQ_KLM
  RFU(1)  = TP_CH_M_DIMM_M1_RFU_1
  A14_WE_N  = M_M_MA<14>
  VDD(3)  = PVDDQ_KLM
  SAVE_N_NC  = FM_ADR_COMPLETE_KLM_N
  VDD(2)  = PVDDQ_KLM
  A13  = M_M_MA<13>
  VDD(1)  = PVDDQ_KLM
  A17  = M_M_MA<17>
  C(2)  = M_M_C<2>
  VDD(0)  = PVDDQ_KLM
  S3_N_C(1)  = M_M_CS_N<7>
  SA(2)  = PVPP_KLM
  VSS(20)  = GND
  DQ(37)  = M_M_DQ<37>
  VSS(19)  = GND
  DQ(33)  = M_M_DQ<33>
  VSS(18)  = GND
  DQS4N  = M_M_DQS_DN<4>
  DQS4P  = M_M_DQS_DP<4>
  VSS(17)  = GND
  DQ(39)  = M_M_DQ<39>
  VSS(16)  = GND
  DQ(35)  = M_M_DQ<35>
  VSS(15)  = GND
  DQ(45)  = M_M_DQ<45>
  VSS(14)  = GND
  DQ(41)  = M_M_DQ<41>
  VSS(13)  = GND
  DQS5N  = M_M_DQS_DN<5>
  DQS5P  = M_M_DQS_DP<5>
  VSS(12)  = GND
  DQ(47)  = M_M_DQ<47>
  VSS(11)  = GND
  DQ(43)  = M_M_DQ<43>
  VSS(10)  = GND
  DQ(53)  = M_M_DQ<53>
  VSS(9)  = GND
  DQ(49)  = M_M_DQ<49>
  VSS(8)  = GND
  DQS6N  = M_M_DQS_DN<6>
  DQS6P  = M_M_DQS_DP<6>
  VSS(7)  = GND
  DQ(55)  = M_M_DQ<55>
  VSS(6)  = GND
  DQ(51)  = M_M_DQ<51>
  VSS(5)  = GND
  DQ(61)  = M_M_DQ<61>
  VSS(4)  = GND
  DQ(57)  = M_M_DQ<57>
  VSS(3)  = GND
  DQS7N  = M_M_DQS_DN<7>
  DQS7P  = M_M_DQS_DP<7>
  VSS(2)  = GND
  DQ(63)  = M_M_DQ<63>
  VSS(1)  = GND
  DQ(59)  = M_M_DQ<59>
  VSS(0)  = GND
  VDDSPD  = PVPP_KLM
  SDA  = SMB_DDR_KLM_VPP_SDA
  VPP(1)  = PVPP_KLM
  VPP(0)  = PVPP_KLM
  VPP(2)  = PVPP_KLM

(kicad_pcb
	(version 20260206)
	(generator "pcbnew")
	(generator_version "10.0")
	(general
		(thickness 1.6)
		(legacy_teardrops no)
	)
	(paper "A4")
	(title_block
		(title "Wiwynn_Tioga_Pass_MB.brd")
		(comment 1 "Tioga Pass / footprint 2717 of 4770 (J9L1), pads 101-151 of 291")
	)
	(layers
		(0 "F.Cu" signal "TOP")
		(4 "In1.Cu" signal "L2GND")
		(6 "In2.Cu" signal "L3")
		(8 "In3.Cu" signal "L4GND")
		(10 "In4.Cu" signal "L5")
		(12 "In5.Cu" signal "L6GND")
		(14 "In6.Cu" signal "L7VCC")
		(16 "In7.Cu" signal "L8VCC")
		(18 "In8.Cu" signal "L9GND")
		(20 "In9.Cu" signal "L10")
		(22 "In10.Cu" signal "L11GND")
		(24 "In11.Cu" signal "L12")
		(26 "In12.Cu" signal "L13GND")
		(2 "B.Cu" signal "BOTTOM")
		(9 "F.Adhes" user "F.Adhesive")
		(11 "B.Adhes" user "B.Adhesive")
		(13 "F.Paste" user "Package Geometry/Pastemask Top")
		(15 "B.Paste" user "Package Geometry/Pastemask Bottom")
		(5 "F.SilkS" user "Ref Des/Silkscreen Top")
		(7 "B.SilkS" user "Ref Des/Silkscreen Bottom")
		(1 "F.Mask" user "Board Geometry/Soldermask Top")
		(3 "B.Mask" user "Board Geometry/Soldermask Bottom")
		(17 "Dwgs.User" user "User.Drawings")
		(19 "Cmts.User" user "User.Comments")
		(21 "Eco1.User" user "User.Eco1")
		(23 "Eco2.User" user "User.Eco2")
		(25 "Edge.Cuts" user "Board Geometry/Outline")
		(27 "Margin" user)
		(31 "F.CrtYd" user "Package Geometry/Place Bound Top")
		(29 "B.CrtYd" user "Package Geometry/Place Bound Bottom")
		(35 "F.Fab" user "Ref Des/Assembly Top")
		(33 "B.Fab" user "Ref Des/Assembly Bottom")
	)
	(footprint ""
		(layer "B.Cu")
		(at 29.699458 -152.078436 90)
		(property "Reference" "J9L1"
			(at 2.200148 37.737542 0)
			(unlocked yes)
			(layer "B.SilkS")
			(effects
				(font
					(size 0.7874 0.5842)
					(thickness 0.1524)
				)
				(justify left mirror)
			)
		)
		(property "Value" ""
			(at 0 0 90)
			(layer "B.Fab")
			(effects
				(font
					(size 1.27 1.27)
				)
				(justify mirror)
			)
		)
		(duplicate_pad_numbers_are_jumpers no)
		(pad "98" smd rect
			(at 0 87.54999 270)
			(size 1.8034 0.508)
			(layers "B.Cu" "B.Mask" "B.Paste")
			(net "GND")
		)
		(pad "99" smd rect
			(at 0 88.399874 270)
			(size 1.8034 0.508)
			(layers "B.Cu" "B.Mask" "B.Paste")
			(net "M_M_DQS_DP<13>")
		)
		(pad "100" smd rect
			(at 0 89.250012 270)
			(size 1.8034 0.508)
			(layers "B.Cu" "B.Mask" "B.Paste")
			(net "M_M_DQS_DN<13>")
		)
		(pad "101" smd rect
			(at 0 90.099896 270)
			(size 1.8034 0.508)
			(layers "B.Cu" "B.Mask" "B.Paste")
			(net "GND")
		)
		(pad "102" smd rect
			(at 0 90.950034 270)
			(size 1.8034 0.508)
			(layers "B.Cu" "B.Mask" "B.Paste")
			(net "M_M_DQ<38>")
		)
		(pad "103" smd rect
			(at 0 91.799918 270)
			(size 1.8034 0.508)
			(layers "B.Cu" "B.Mask" "B.Paste")
			(net "GND")
		)
		(pad "104" smd rect
			(at 0 92.650056 270)
			(size 1.8034 0.508)
			(layers "B.Cu" "B.Mask" "B.Paste")
			(net "M_M_DQ<34>")
		)
		(pad "105" smd rect
			(at 0 93.49994 270)
			(size 1.8034 0.508)
			(layers "B.Cu" "B.Mask" "B.Paste")
			(net "GND")
		)
		(pad "106" smd rect
			(at 0 94.350078 270)
			(size 1.8034 0.508)
			(layers "B.Cu" "B.Mask" "B.Paste")
			(net "M_M_DQ<44>")
		)
		(pad "107" smd rect
			(at 0 95.199962 270)
			(size 1.8034 0.508)
			(layers "B.Cu" "B.Mask" "B.Paste")
			(net "GND")
		)
		(pad "108" smd rect
			(at 0 96.0501 270)
			(size 1.8034 0.508)
			(layers "B.Cu" "B.Mask" "B.Paste")
			(net "M_M_DQ<40>")
		)
		(pad "109" smd rect
			(at 0 96.899984 270)
			(size 1.8034 0.508)
			(layers "B.Cu" "B.Mask" "B.Paste")
			(net "GND")
		)
		(pad "110" smd rect
			(at 0 97.750122 270)
			(size 1.8034 0.508)
			(layers "B.Cu" "B.Mask" "B.Paste")
			(net "M_M_DQS_DP<14>")
		)
		(pad "111" smd rect
			(at 0 98.600006 270)
			(size 1.8034 0.508)
			(layers "B.Cu" "B.Mask" "B.Paste")
			(net "M_M_DQS_DN<14>")
		)
		(pad "112" smd rect
			(at 0 99.44989 270)
			(size 1.8034 0.508)
			(layers "B.Cu" "B.Mask" "B.Paste")
			(net "GND")
		)
		(pad "113" smd rect
			(at 0 100.300028 270)
			(size 1.8034 0.508)
			(layers "B.Cu" "B.Mask" "B.Paste")
			(net "M_M_DQ<46>")
		)
		(pad "114" smd rect
			(at 0 101.149912 270)
			(size 1.8034 0.508)
			(layers "B.Cu" "B.Mask" "B.Paste")
			(net "GND")
		)
		(pad "115" smd rect
			(at 0 102.00005 270)
			(size 1.8034 0.508)
			(layers "B.Cu" "B.Mask" "B.Paste")
			(net "M_M_DQ<42>")
		)
		(pad "116" smd rect
			(at 0 102.849934 270)
			(size 1.8034 0.508)
			(layers "B.Cu" "B.Mask" "B.Paste")
			(net "GND")
		)
		(pad "117" smd rect
			(at 0 103.700072 270)
			(size 1.8034 0.508)
			(layers "B.Cu" "B.Mask" "B.Paste")
			(net "M_M_DQ<52>")
		)
		(pad "118" smd rect
			(at 0 104.549956 270)
			(size 1.8034 0.508)
			(layers "B.Cu" "B.Mask" "B.Paste")
			(net "GND")
		)
		(pad "119" smd rect
			(at 0 105.400094 270)
			(size 1.8034 0.508)
			(layers "B.Cu" "B.Mask" "B.Paste")
			(net "M_M_DQ<48>")
		)
		(pad "120" smd rect
			(at 0 106.249978 270)
			(size 1.8034 0.508)
			(layers "B.Cu" "B.Mask" "B.Paste")
			(net "GND")
		)
		(pad "121" smd rect
			(at 0 107.100116 270)
			(size 1.8034 0.508)
			(layers "B.Cu" "B.Mask" "B.Paste")
			(net "M_M_DQS_DP<15>")
		)
		(pad "122" smd rect
			(at 0 107.95 270)
			(size 1.8034 0.508)
			(layers "B.Cu" "B.Mask" "B.Paste")
			(net "M_M_DQS_DN<15>")
		)
		(pad "123" smd rect
			(at 0 108.799884 270)
			(size 1.8034 0.508)
			(layers "B.Cu" "B.Mask" "B.Paste")
			(net "GND")
		)
		(pad "124" smd rect
			(at 0 109.650022 270)
			(size 1.8034 0.508)
			(layers "B.Cu" "B.Mask" "B.Paste")
			(net "M_M_DQ<54>")
		)
		(pad "125" smd rect
			(at 0 110.499906 270)
			(size 1.8034 0.508)
			(layers "B.Cu" "B.Mask" "B.Paste")
			(net "GND")
		)
		(pad "126" smd rect
			(at 0 111.350044 270)
			(size 1.8034 0.508)
			(layers "B.Cu" "B.Mask" "B.Paste")
			(net "M_M_DQ<50>")
		)
		(pad "127" smd rect
			(at 0 112.199928 270)
			(size 1.8034 0.508)
			(layers "B.Cu" "B.Mask" "B.Paste")
			(net "GND")
		)
		(pad "128" smd rect
			(at 0 113.050066 270)
			(size 1.8034 0.508)
			(layers "B.Cu" "B.Mask" "B.Paste")
			(net "M_M_DQ<60>")
		)
		(pad "129" smd rect
			(at 0 113.89995 270)
			(size 1.8034 0.508)
			(layers "B.Cu" "B.Mask" "B.Paste")
			(net "GND")
		)
		(pad "130" smd rect
			(at 0 114.750088 270)
			(size 1.8034 0.508)
			(layers "B.Cu" "B.Mask" "B.Paste")
			(net "M_M_DQ<56>")
		)
		(pad "131" smd rect
			(at 0 115.599972 270)
			(size 1.8034 0.508)
			(layers "B.Cu" "B.Mask" "B.Paste")
			(net "GND")
		)
		(pad "132" smd rect
			(at 0 116.45011 270)
			(size 1.8034 0.508)
			(layers "B.Cu" "B.Mask" "B.Paste")
			(net "M_M_DQS_DP<16>")
		)
		(pad "133" smd rect
			(at 0 117.299994 270)
			(size 1.8034 0.508)
			(layers "B.Cu" "B.Mask" "B.Paste")
			(net "M_M_DQS_DN<16>")
		)
		(pad "134" smd rect
			(at 0 118.149878 270)
			(size 1.8034 0.508)
			(layers "B.Cu" "B.Mask" "B.Paste")
			(net "GND")
		)
		(pad "135" smd rect
			(at 0 119.000016 270)
			(size 1.8034 0.508)
			(layers "B.Cu" "B.Mask" "B.Paste")
			(net "M_M_DQ<62>")
		)
		(pad "136" smd rect
			(at 0 119.8499 270)
			(size 1.8034 0.508)
			(layers "B.Cu" "B.Mask" "B.Paste")
			(net "GND")
		)
		(pad "137" smd rect
			(at 0 120.700038 270)
			(size 1.8034 0.508)
			(layers "B.Cu" "B.Mask" "B.Paste")
			(net "M_M_DQ<58>")
		)
		(pad "138" smd rect
			(at 0 121.549922 270)
			(size 1.8034 0.508)
			(layers "B.Cu" "B.Mask" "B.Paste")
			(net "GND")
		)
		(pad "139" smd rect
			(at 0 122.40006 270)
			(size 1.8034 0.508)
			(layers "B.Cu" "B.Mask" "B.Paste")
			(net "PVPP_KLM")
		)
		(pad "140" smd rect
			(at 0 123.249944 270)
			(size 1.8034 0.508)
			(layers "B.Cu" "B.Mask" "B.Paste")
			(net "GND")
		)
		(pad "141" smd rect
			(at 0 124.100082 270)
			(size 1.8034 0.508)
			(layers "B.Cu" "B.Mask" "B.Paste")
			(net "SMB_DDR_KLM_VPP_SCL")
		)
		(pad "142" smd rect
			(at 0 124.949966 270)
			(size 1.8034 0.508)
			(layers "B.Cu" "B.Mask" "B.Paste")
			(net "PVPP_KLM")
		)
		(pad "143" smd rect
			(at 0 125.800104 270)
			(size 1.8034 0.508)
			(layers "B.Cu" "B.Mask" "B.Paste")
			(net "PVPP_KLM")
		)
		(pad "144" smd rect
			(at 0 126.649988 270)
			(size 1.8034 0.508)
			(layers "B.Cu" "B.Mask" "B.Paste")
			(net "TP_CH_M_DIMM_M1_RFU_2")
		)
		(pad "145" smd rect
			(at -4.59994 0 270)
			(size 1.8034 0.508)
			(layers "B.Cu" "B.Mask" "B.Paste")
			(net "P12V_NVDIMM_KLM")
		)
		(pad "146" smd rect
			(at -4.59994 0.849884 270)
			(size 1.8034 0.508)
			(layers "B.Cu" "B.Mask" "B.Paste")
			(net "M_M_VREF")
		)
		(pad "147" smd rect
			(at -4.59994 1.700022 270)
			(size 1.8034 0.508)
			(layers "B.Cu" "B.Mask" "B.Paste")
			(net "GND")
		)
		(pad "148" smd rect
			(at -4.59994 2.549906 270)
			(size 1.8034 0.508)
			(layers "B.Cu" "B.Mask" "B.Paste")
			(net "M_M_DQ<5>")
		)
	)
)
